# BASEBOARD_FAB2 (Tioga Pass) — schematic netlist excerpt (pin names and nets, part order shuffled) for the footprints in the layout excerpt that follows; sources: Cadence DE-HDL packaged netlist, KiCad conversion of Wiwynn_Tioga_Pass_MB.brd

C6D9  CAP_A  22.0UF 4V 20% X6S  pkg 0603V  page 42 : A = PVCCIO_CPU0 ; B = GND
C5D19  CAP_A  22.0UF 4V 20% X6S  pkg 0603V  page 42 : A = PVCCIN_CPU0 ; B = GND
C4A11  CAP  4.7UF 6.3V 10% X6S  pkg 0603  page 222 : A = VSENSE_PVDDQ_DEF_VTT ; B = GND

(kicad_pcb
	(version 20260206)
	(generator "pcbnew")
	(generator_version "10.0")
	(general
		(thickness 1.6)
		(legacy_teardrops no)
	)
	(paper "A4")
	(title_block
		(title "Wiwynn_Tioga_Pass_MB.brd")
		(comment 1 "Tioga Pass / footprints 1746-1748 of 4770")
	)
	(layers
		(0 "F.Cu" signal "TOP")
		(4 "In1.Cu" signal "L2GND")
		(6 "In2.Cu" signal "L3")
		(8 "In3.Cu" signal "L4GND")
		(10 "In4.Cu" signal "L5")
		(12 "In5.Cu" signal "L6GND")
		(14 "In6.Cu" signal "L7VCC")
		(16 "In7.Cu" signal "L8VCC")
		(18 "In8.Cu" signal "L9GND")
		(20 "In9.Cu" signal "L10")
		(22 "In10.Cu" signal "L11GND")
		(24 "In11.Cu" signal "L12")
		(26 "In12.Cu" signal "L13GND")
		(2 "B.Cu" signal "BOTTOM")
		(9 "F.Adhes" user "F.Adhesive")
		(11 "B.Adhes" user "B.Adhesive")
		(13 "F.Paste" user "Package Geometry/Pastemask Top")
		(15 "B.Paste" user "Package Geometry/Pastemask Bottom")
		(5 "F.SilkS" user "Ref Des/Silkscreen Top")
		(7 "B.SilkS" user "Ref Des/Silkscreen Bottom")
		(1 "F.Mask" user "Board Geometry/Soldermask Top")
		(3 "B.Mask" user "Board Geometry/Soldermask Bottom")
		(17 "Dwgs.User" user "User.Drawings")
		(19 "Cmts.User" user "User.Comments")
		(21 "Eco1.User" user "User.Eco1")
		(23 "Eco2.User" user "User.Eco2")
		(25 "Edge.Cuts" user "Board Geometry/Outline")
		(27 "Margin" user)
		(31 "F.CrtYd" user "Package Geometry/Place Bound Top")
		(29 "B.CrtYd" user "Package Geometry/Place Bound Bottom")
		(35 "F.Fab" user "Ref Des/Assembly Top")
		(33 "B.Fab" user "Ref Des/Assembly Bottom")
	)
	(footprint ""
		(layer "F.Cu")
		(at 182.6514 -146.685)
		(property "Reference" "C4A11"
			(at 0 0 0)
			(layer "F.SilkS")
			(hide yes)
			(effects
				(font
					(size 1.27 1.27)
				)
			)
		)
		(property "Value" ""
			(at 0 0 0)
			(layer "F.Fab")
			(effects
				(font
					(size 1.27 1.27)
				)
			)
		)
		(duplicate_pad_numbers_are_jumpers no)
		(fp_poly
			(pts
				(xy -0.4953 -0.2032) (xy 0.4953 -0.2032) (xy 0.4953 1.6002) (xy -0.4953 1.6002)
			)
			(stroke
				(width 0)
				(type default)
			)
			(fill no)
			(layer "F.CrtYd")
		)
		(fp_line
			(start -0.4953 -0.2032)
			(end 0.4953 -0.2032)
			(stroke
				(width 0.1)
				(type default)
			)
			(layer "F.Fab")
		)
		(fp_line
			(start -0.4953 1.6002)
			(end -0.4953 -0.2032)
			(stroke
				(width 0.1)
				(type default)
			)
			(layer "F.Fab")
		)
		(fp_line
			(start 0.4953 -0.2032)
			(end 0.4953 1.6002)
			(stroke
				(width 0.1)
				(type default)
			)
			(layer "F.Fab")
		)
		(fp_line
			(start 0.4953 1.6002)
			(end -0.4953 1.6002)
			(stroke
				(width 0.1)
				(type default)
			)
			(layer "F.Fab")
		)
		(pad "1" smd rect
			(at 0 0)
			(size 0.762 0.889)
			(layers "F.Cu" "F.Mask" "F.Paste")
			(net "VSENSE_PVDDQ_DEF_VTT")
		)
		(pad "2" smd rect
			(at 0 1.397)
			(size 0.762 0.889)
			(layers "F.Cu" "F.Mask" "F.Paste")
			(net "GND")
		)
		(zone
			(layer "F.Cu")
			(hatch none 0.5)
			(connect_pads
				(clearance 0)
			)
			(min_thickness 0.25)
			(keepout
				(tracks not_allowed)
				(vias allowed)
				(pads allowed)
				(copperpour not_allowed)
				(footprints allowed)
			)
			(placement
				(enabled no)
				(sheetname "")
			)
			(fill
				(thermal_gap 0.5)
				(thermal_bridge_width 0.5)
				(island_removal_mode 0)
			)
			(polygon
				(pts
					(xy 182.2704 -146.2405) (xy 183.0324 -146.2405) (xy 183.0324 -145.7325) (xy 182.2704 -145.7325)
				)
			)
		)
	)
	(footprint ""
		(layer "F.Cu")
		(at 278.868124 -71.714614 180)
		(property "Reference" "C6D9"
			(at 0 0 180)
			(layer "F.SilkS")
			(hide yes)
			(effects
				(font
					(size 1.27 1.27)
				)
			)
		)
		(property "Value" ""
			(at 0 0 180)
			(layer "F.Fab")
			(effects
				(font
					(size 1.27 1.27)
				)
			)
		)
		(duplicate_pad_numbers_are_jumpers no)
		(fp_poly
			(pts
				(xy -0.4953 -0.2032) (xy 0.4953 -0.2032) (xy 0.4953 1.6002) (xy -0.4953 1.6002)
			)
			(stroke
				(width 0)
				(type default)
			)
			(fill no)
			(layer "F.CrtYd")
		)
		(fp_line
			(start 0.4953 1.6002)
			(end -0.4953 1.6002)
			(stroke
				(width 0.1)
				(type default)
			)
			(layer "F.Fab")
		)
		(fp_line
			(start 0.4953 -0.2032)
			(end 0.4953 1.6002)
			(stroke
				(width 0.1)
				(type default)
			)
			(layer "F.Fab")
		)
		(fp_line
			(start -0.4953 1.6002)
			(end -0.4953 -0.2032)
			(stroke
				(width 0.1)
				(type default)
			)
			(layer "F.Fab")
		)
		(fp_line
			(start -0.4953 -0.2032)
			(end 0.4953 -0.2032)
			(stroke
				(width 0.1)
				(type default)
			)
			(layer "F.Fab")
		)
		(pad "1" smd rect
			(at 0 0 180)
			(size 0.762 0.889)
			(layers "F.Cu" "F.Mask" "F.Paste")
			(net "PVCCIO_CPU0")
		)
		(pad "2" smd rect
			(at 0 1.397 180)
			(size 0.762 0.889)
			(layers "F.Cu" "F.Mask" "F.Paste")
			(net "GND")
		)
		(zone
			(layer "F.Cu")
			(hatch none 0.5)
			(connect_pads
				(clearance 0)
			)
			(min_thickness 0.25)
			(keepout
				(tracks not_allowed)
				(vias allowed)
				(pads allowed)
				(copperpour not_allowed)
				(footprints allowed)
			)
			(placement
				(enabled no)
				(sheetname "")
			)
			(fill
				(thermal_gap 0.5)
				(thermal_bridge_width 0.5)
				(island_removal_mode 0)
			)
			(polygon
				(pts
					(xy 279.249124 -72.159114) (xy 278.487124 -72.159114) (xy 278.487124 -72.667114) (xy 279.249124 -72.667114)
				)
			)
		)
	)
	(footprint ""
		(layer "F.Cu")
		(at 268.1732 -79.6036 180)
		(property "Reference" "C5D19"
			(at 0 0 180)
			(layer "F.SilkS")
			(hide yes)
			(effects
				(font
					(size 1.27 1.27)
				)
			)
		)
		(property "Value" ""
			(at 0 0 180)
			(layer "F.Fab")
			(effects
				(font
					(size 1.27 1.27)
				)
			)
		)
		(duplicate_pad_numbers_are_jumpers no)
		(fp_poly
			(pts
				(xy -0.4953 -0.2032) (xy 0.4953 -0.2032) (xy 0.4953 1.6002) (xy -0.4953 1.6002)
			)
			(stroke
				(width 0)
				(type default)
			)
			(fill no)
			(layer "F.CrtYd")
		)
		(fp_line
			(start 0.4953 1.6002)
			(end -0.4953 1.6002)
			(stroke
				(width 0.1)
				(type default)
			)
			(layer "F.Fab")
		)
		(fp_line
			(start 0.4953 -0.2032)
			(end 0.4953 1.6002)
			(stroke
				(width 0.1)
				(type default)
			)
			(layer "F.Fab")
		)
		(fp_line
			(start -0.4953 1.6002)
			(end -0.4953 -0.2032)
			(stroke
				(width 0.1)
				(type default)
			)
			(layer "F.Fab")
		)
		(fp_line
			(start -0.4953 -0.2032)
			(end 0.4953 -0.2032)
			(stroke
				(width 0.1)
				(type default)
			)
			(layer "F.Fab")
		)
		(pad "1" smd rect
			(at 0 0 180)
			(size 0.762 0.889)
			(layers "F.Cu" "F.Mask" "F.Paste")
			(net "PVCCIN_CPU0")
		)
		(pad "2" smd rect
			(at 0 1.397 180)
			(size 0.762 0.889)
			(layers "F.Cu" "F.Mask" "F.Paste")
			(net "GND")
		)
		(zone
			(layer "F.Cu")
			(hatch none 0.5)
			(connect_pads
				(clearance 0)
			)
			(min_thickness 0.25)
			(keepout
				(tracks not_allowed)
				(vias allowed)
				(pads allowed)
				(copperpour not_allowed)
				(footprints allowed)
			)
			(placement
				(enabled no)
				(sheetname "")
			)
			(fill
				(thermal_gap 0.5)
				(thermal_bridge_width 0.5)
				(island_removal_mode 0)
			)
			(polygon
				(pts
					(xy 268.5542 -80.0481) (xy 267.7922 -80.0481) (xy 267.7922 -80.5561) (xy 268.5542 -80.5561)
				)
			)
		)
	)
)
